(kicad_pcb
	(version 20260206)
	(generator "pcbnew")
	(generator_version "10.0")
	(general
		(thickness 1.6)
		(legacy_teardrops no)
	)
	(paper "A4")
	(title_block
		(title "netronome-mezz — pcbd0082-001_rev01_jul9_a.brd")
		(comment 1 "Open CloudServer (Microsoft) / footprints 7-12 of 714")
	)
	(layers
		(0 "F.Cu" signal "TOP")
		(4 "In1.Cu" signal "02_GND")
		(6 "In2.Cu" signal "03_SIG")
		(8 "In3.Cu" signal "04_SIG")
		(10 "In4.Cu" signal "05_GND")
		(12 "In5.Cu" signal "06_PWR1")
		(14 "In6.Cu" signal "07_SIG")
		(16 "In7.Cu" signal "08_SIG")
		(18 "In8.Cu" signal "09_GND")
		(2 "B.Cu" signal "BOTTOM")
		(9 "F.Adhes" user "F.Adhesive")
		(11 "B.Adhes" user "B.Adhesive")
		(13 "F.Paste" user "Package Geometry/Pastemask Top")
		(15 "B.Paste" user "Package Geometry/Pastemask Bottom")
		(5 "F.SilkS" user "Ref Des/Silkscreen Top")
		(7 "B.SilkS" user "Ref Des/Silkscreen Bottom")
		(1 "F.Mask" user "Board Geometry/Soldermask Top")
		(3 "B.Mask" user "Board Geometry/Soldermask Bottom")
		(17 "Dwgs.User" user "User.Drawings")
		(19 "Cmts.User" user "User.Comments")
		(21 "Eco1.User" user "User.Eco1")
		(23 "Eco2.User" user "User.Eco2")
		(25 "Edge.Cuts" user "Board Geometry/Outline")
		(27 "Margin" user)
		(31 "F.CrtYd" user "Package Geometry/Place Bound Top")
		(29 "B.CrtYd" user "Package Geometry/Place Bound Bottom")
		(35 "F.Fab" user "Ref Des/Assembly Top")
		(33 "B.Fab" user "Ref Des/Assembly Bottom")
		(45 "User.4" user "COMPVAL_TYPE_BOTTOM")
	)
	(footprint ""
		(layer "F.Cu")
		(at 14.732 40.894 90)
		(property "Reference" "C133"
			(at 0.86233 -1.524 0)
			(unlocked yes)
			(layer "F.SilkS")
			(effects
				(font
					(size 0.7874 0.5842)
					(thickness 0.127)
				)
				(justify left)
			)
		)
		(property "Value" "10UF"
			(at -0.148158 1.7526 180)
			(unlocked yes)
			(layer "F.Fab")
			(hide yes)
			(effects
				(font
					(size 1.27 0.9652)
					(thickness 0.000001)
				)
				(justify left)
			)
		)
		(property "Device Type" "CAPC0058"
			(at -0.148158 1.7526 180)
			(unlocked yes)
			(layer "F.Fab")
			(hide yes)
			(effects
				(font
					(size 1.27 0.9652)
					(thickness 0.000001)
				)
				(justify left)
			)
		)
		(duplicate_pad_numbers_are_jumpers no)
		(fp_circle
			(center 0 0)
			(end 0 0.127)
			(stroke
				(width 0.2032)
				(type default)
			)
			(fill no)
			(layer "F.SilkS")
		)
		(fp_poly
			(pts
				(xy 0.7874 -1.6637) (xy -0.7874 -1.6637) (xy -0.7874 1.6637) (xy 0.7874 1.6637)
			)
			(stroke
				(width 0)
				(type default)
			)
			(fill no)
			(layer "F.CrtYd")
		)
		(fp_line
			(start 0.4064 -0.7874)
			(end 0.4064 0.8128)
			(stroke
				(width 0.0254)
				(type default)
			)
			(layer "F.Fab")
		)
		(fp_line
			(start -0.4064 -0.7874)
			(end 0.4064 -0.7874)
			(stroke
				(width 0.0254)
				(type default)
			)
			(layer "F.Fab")
		)
		(fp_line
			(start 0.4064 0.8128)
			(end -0.4064 0.8128)
			(stroke
				(width 0.0254)
				(type default)
			)
			(layer "F.Fab")
		)
		(fp_line
			(start -0.4064 0.8128)
			(end -0.4064 -0.7874)
			(stroke
				(width 0.0254)
				(type default)
			)
			(layer "F.Fab")
		)
		(pad "1" smd rect
			(at 0 -0.8001 90)
			(size 0.8636 0.9652)
			(layers "F.Cu" "F.Mask" "F.Paste")
			(net "VDD_5.0V")
		)
		(pad "2" smd rect
			(at 0 0.8001 90)
			(size 0.8636 0.9652)
			(layers "F.Cu" "F.Mask" "F.Paste")
			(net "GND")
		)
	)
	(footprint ""
		(layer "F.Cu")
		(at 42.418 51.816 180)
		(property "Reference" "R317"
			(at 3.302 -0.02667 0)
			(unlocked yes)
			(layer "F.SilkS")
			(effects
				(font
					(size 0.7874 0.5842)
					(thickness 0.127)
				)
				(justify left)
			)
		)
		(property "Value" "1.0K"
			(at -0.148158 1.3462 270)
			(unlocked yes)
			(layer "F.Fab")
			(hide yes)
			(effects
				(font
					(size 1.27 0.9652)
					(thickness 0.000001)
				)
				(justify left)
			)
		)
		(property "Device Type" "REST0025"
			(at -0.148158 1.3462 270)
			(unlocked yes)
			(layer "F.Fab")
			(hide yes)
			(effects
				(font
					(size 1.27 0.9652)
					(thickness 0.000001)
				)
				(justify left)
			)
		)
		(duplicate_pad_numbers_are_jumpers no)
		(fp_poly
			(pts
				(xy 0.635 1.0668) (xy 0.635 -1.0668) (xy -0.635 -1.0668) (xy -0.635 1.0668)
			)
			(stroke
				(width 0)
				(type default)
			)
			(fill no)
			(layer "F.CrtYd")
		)
		(fp_line
			(start 0.254 0.508)
			(end -0.254 0.508)
			(stroke
				(width 0.0254)
				(type default)
			)
			(layer "F.Fab")
		)
		(fp_line
			(start 0.254 -0.508)
			(end 0.254 0.508)
			(stroke
				(width 0.0254)
				(type default)
			)
			(layer "F.Fab")
		)
		(fp_line
			(start -0.254 0.508)
			(end -0.254 -0.508)
			(stroke
				(width 0.0254)
				(type default)
			)
			(layer "F.Fab")
		)
		(fp_line
			(start -0.254 -0.508)
			(end 0.254 -0.508)
			(stroke
				(width 0.0254)
				(type default)
			)
			(layer "F.Fab")
		)
		(pad "1" smd rect
			(at 0 -0.4191 180)
			(size 0.508 0.5334)
			(layers "F.Cu" "F.Mask" "F.Paste")
			(net "GND")
		)
		(pad "2" smd rect
			(at 0 0.4191 180)
			(size 0.508 0.5334)
			(layers "F.Cu" "F.Mask" "F.Paste")
			(net "EXT_12.0V_THRESHOLD")
		)
		(zone
			(layer "F.Cu")
			(hatch none 0.5)
			(connect_pads
				(clearance 0)
			)
			(min_thickness 0.25)
			(keepout
				(tracks not_allowed)
				(vias allowed)
				(pads allowed)
				(copperpour not_allowed)
				(footprints allowed)
			)
			(placement
				(enabled no)
				(sheetname "")
			)
			(fill
				(thermal_gap 0.5)
				(thermal_bridge_width 0.5)
				(island_removal_mode 0)
			)
			(polygon
				(pts
					(xy 42.3926 51.8414) (xy 42.3926 51.7906) (xy 42.4434 51.7906) (xy 42.4434 51.8414)
				)
			)
		)
	)
	(footprint ""
		(layer "F.Cu")
		(at 75.451005 7.498994)
		(property "Reference" "V_A-DQ07"
			(at 0 0 0)
			(layer "F.SilkS")
			(hide yes)
			(effects
				(font
					(size 1.27 1.27)
				)
			)
		)
		(property "Value" ""
			(at 0 0 0)
			(layer "F.Fab")
			(effects
				(font
					(size 1.27 1.27)
				)
			)
		)
		(duplicate_pad_numbers_are_jumpers no)
		(pad "1" thru_hole circle
			(at 0 0)
			(size 0.762 0.762)
			(drill 0.20574)
			(layers "*.Cu" "*.Mask")
			(remove_unused_layers no)
			(net "DDR0_32A_DQ7")
			(clearance 0.127)
			(thermal_gap 0.127)
			(padstack
				(mode front_inner_back)
				(layer "Inner"
					(shape circle)
					(size 0.4572 0.4572)
					(clearance 0.1143)
				)
				(layer "B.Cu"
					(shape circle)
					(size 0.4572 0.4572)
					(clearance 0.1143)
				)
			)
		)
	)
	(footprint ""
		(layer "F.Cu")
		(at 84.582 26.924)
		(property "Reference" "R219"
			(at 0 -1.24333 0)
			(unlocked yes)
			(layer "F.SilkS")
			(effects
				(font
					(size 0.7874 0.5842)
					(thickness 0.127)
				)
				(justify left)
			)
		)
		(property "Value" "39.0"
			(at -0.148158 1.3462 90)
			(unlocked yes)
			(layer "F.Fab")
			(hide yes)
			(effects
				(font
					(size 1.27 0.9652)
					(thickness 0.000001)
				)
				(justify left)
			)
		)
		(property "Device Type" "REST0108"
			(at -0.148158 1.3462 90)
			(unlocked yes)
			(layer "F.Fab")
			(hide yes)
			(effects
				(font
					(size 1.27 0.9652)
					(thickness 0.000001)
				)
				(justify left)
			)
		)
		(duplicate_pad_numbers_are_jumpers no)
		(fp_poly
			(pts
				(xy 0.635 1.0668) (xy 0.635 -1.0668) (xy -0.635 -1.0668) (xy -0.635 1.0668)
			)
			(stroke
				(width 0)
				(type default)
			)
			(fill no)
			(layer "F.CrtYd")
		)
		(fp_line
			(start -0.254 -0.508)
			(end 0.254 -0.508)
			(stroke
				(width 0.0254)
				(type default)
			)
			(layer "F.Fab")
		)
		(fp_line
			(start -0.254 0.508)
			(end -0.254 -0.508)
			(stroke
				(width 0.0254)
				(type default)
			)
			(layer "F.Fab")
		)
		(fp_line
			(start 0.254 -0.508)
			(end 0.254 0.508)
			(stroke
				(width 0.0254)
				(type default)
			)
			(layer "F.Fab")
		)
		(fp_line
			(start 0.254 0.508)
			(end -0.254 0.508)
			(stroke
				(width 0.0254)
				(type default)
			)
			(layer "F.Fab")
		)
		(pad "1" smd rect
			(at 0 -0.4191)
			(size 0.508 0.5334)
			(layers "F.Cu" "F.Mask" "F.Paste")
			(net "DDR0_32A_A13")
		)
		(pad "2" smd rect
			(at 0 0.4191)
			(size 0.508 0.5334)
			(layers "F.Cu" "F.Mask" "F.Paste")
			(net "DDR_VTT")
		)
		(zone
			(layer "F.Cu")
			(hatch none 0.5)
			(connect_pads
				(clearance 0)
			)
			(min_thickness 0.25)
			(keepout
				(tracks not_allowed)
				(vias allowed)
				(pads allowed)
				(copperpour not_allowed)
				(footprints allowed)
			)
			(placement
				(enabled no)
				(sheetname "")
			)
			(fill
				(thermal_gap 0.5)
				(thermal_bridge_width 0.5)
				(island_removal_mode 0)
			)
			(polygon
				(pts
					(xy 84.6074 26.8986) (xy 84.6074 26.9494) (xy 84.5566 26.9494) (xy 84.5566 26.8986)
				)
			)
		)
	)
	(footprint ""
		(layer "F.Cu")
		(at 83.693 28.702 180)
		(property "Reference" "R217"
			(at 0 0 180)
			(layer "F.SilkS")
			(hide yes)
			(effects
				(font
					(size 1.27 1.27)
				)
			)
		)
		(property "Value" "39.0"
			(at -0.148158 1.3462 270)
			(unlocked yes)
			(layer "F.Fab")
			(hide yes)
			(effects
				(font
					(size 1.27 0.9652)
					(thickness 0.000001)
				)
				(justify left)
			)
		)
		(property "Device Type" "REST0108"
			(at -0.148158 1.3462 270)
			(unlocked yes)
			(layer "F.Fab")
			(hide yes)
			(effects
				(font
					(size 1.27 0.9652)
					(thickness 0.000001)
				)
				(justify left)
			)
		)
		(duplicate_pad_numbers_are_jumpers no)
		(fp_poly
			(pts
				(xy 0.635 1.0668) (xy 0.635 -1.0668) (xy -0.635 -1.0668) (xy -0.635 1.0668)
			)
			(stroke
				(width 0)
				(type default)
			)
			(fill no)
			(layer "F.CrtYd")
		)
		(fp_line
			(start 0.254 0.508)
			(end -0.254 0.508)
			(stroke
				(width 0.0254)
				(type default)
			)
			(layer "F.Fab")
		)
		(fp_line
			(start 0.254 -0.508)
			(end 0.254 0.508)
			(stroke
				(width 0.0254)
				(type default)
			)
			(layer "F.Fab")
		)
		(fp_line
			(start -0.254 0.508)
			(end -0.254 -0.508)
			(stroke
				(width 0.0254)
				(type default)
			)
			(layer "F.Fab")
		)
		(fp_line
			(start -0.254 -0.508)
			(end 0.254 -0.508)
			(stroke
				(width 0.0254)
				(type default)
			)
			(layer "F.Fab")
		)
		(pad "1" smd rect
			(at 0 -0.4191 180)
			(size 0.508 0.5334)
			(layers "F.Cu" "F.Mask" "F.Paste")
			(net "DDR0_32A_A11")
		)
		(pad "2" smd rect
			(at 0 0.4191 180)
			(size 0.508 0.5334)
			(layers "F.Cu" "F.Mask" "F.Paste")
			(net "DDR_VTT")
		)
		(zone
			(layer "F.Cu")
			(hatch none 0.5)
			(connect_pads
				(clearance 0)
			)
			(min_thickness 0.25)
			(keepout
				(tracks not_allowed)
				(vias allowed)
				(pads allowed)
				(copperpour not_allowed)
				(footprints allowed)
			)
			(placement
				(enabled no)
				(sheetname "")
			)
			(fill
				(thermal_gap 0.5)
				(thermal_bridge_width 0.5)
				(island_removal_mode 0)
			)
			(polygon
				(pts
					(xy 83.6676 28.7274) (xy 83.6676 28.6766) (xy 83.7184 28.6766) (xy 83.7184 28.7274)
				)
			)
		)
	)
	(footprint ""
		(layer "F.Cu")
		(at 79.1972 22.987 180)
		(property "Reference" "R229"
			(at 0 0 180)
			(layer "F.SilkS")
			(hide yes)
			(effects
				(font
					(size 1.27 1.27)
				)
			)
		)
		(property "Value" "39.0"
			(at -0.148158 1.3462 270)
			(unlocked yes)
			(layer "F.Fab")
			(hide yes)
			(effects
				(font
					(size 1.27 0.9652)
					(thickness 0.000001)
				)
				(justify left)
			)
		)
		(property "Device Type" "REST0108"
			(at -0.148158 1.3462 270)
			(unlocked yes)
			(layer "F.Fab")
			(hide yes)
			(effects
				(font
					(size 1.27 0.9652)
					(thickness 0.000001)
				)
				(justify left)
			)
		)
		(duplicate_pad_numbers_are_jumpers no)
		(fp_poly
			(pts
				(xy 0.635 1.0668) (xy 0.635 -1.0668) (xy -0.635 -1.0668) (xy -0.635 1.0668)
			)
			(stroke
				(width 0)
				(type default)
			)
			(fill no)
			(layer "F.CrtYd")
		)
		(fp_line
			(start 0.254 0.508)
			(end -0.254 0.508)
			(stroke
				(width 0.0254)
				(type default)
			)
			(layer "F.Fab")
		)
		(fp_line
			(start 0.254 -0.508)
			(end 0.254 0.508)
			(stroke
				(width 0.0254)
				(type default)
			)
			(layer "F.Fab")
		)
		(fp_line
			(start -0.254 0.508)
			(end -0.254 -0.508)
			(stroke
				(width 0.0254)
				(type default)
			)
			(layer "F.Fab")
		)
		(fp_line
			(start -0.254 -0.508)
			(end 0.254 -0.508)
			(stroke
				(width 0.0254)
				(type default)
			)
			(layer "F.Fab")
		)
		(pad "1" smd rect
			(at 0 -0.4191 180)
			(size 0.508 0.5334)
			(layers "F.Cu" "F.Mask" "F.Paste")
			(net "DDR0_32A_CS0_L")
		)
		(pad "2" smd rect
			(at 0 0.4191 180)
			(size 0.508 0.5334)
			(layers "F.Cu" "F.Mask" "F.Paste")
			(net "DDR_VTT")
		)
		(zone
			(layer "F.Cu")
			(hatch none 0.5)
			(connect_pads
				(clearance 0)
			)
			(min_thickness 0.25)
			(keepout
				(tracks not_allowed)
				(vias allowed)
				(pads allowed)
				(copperpour not_allowed)
				(footprints allowed)
			)
			(placement
				(enabled no)
				(sheetname "")
			)
			(fill
				(thermal_gap 0.5)
				(thermal_bridge_width 0.5)
				(island_removal_mode 0)
			)
			(polygon
				(pts
					(xy 79.1718 23.0124) (xy 79.1718 22.9616) (xy 79.2226 22.9616) (xy 79.2226 23.0124)
				)
			)
		)
	)
)
